(kicad_pcb
	(version 20260206)
	(generator "pcbnew")
	(generator_version "10.0")
	(general
		(thickness 1.6)
		(legacy_teardrops no)
	)
	(paper "A4")
	(title_block
		(title "01162023_DA0F0TEBIF0_F0T_Expander_BD_F_brd_V02_OCP.brd")
		(comment 1 "Grand Teton / footprints 4452-4455 of 9728")
	)
	(layers
		(0 "F.Cu" signal "TOP")
		(4 "In1.Cu" signal "GND")
		(6 "In2.Cu" signal "VCC")
		(8 "In3.Cu" signal "VCC1")
		(10 "In4.Cu" signal "GND1")
		(12 "In5.Cu" signal "IN1")
		(14 "In6.Cu" signal "GND2")
		(16 "In7.Cu" signal "IN2")
		(18 "In8.Cu" signal "GND3")
		(20 "In9.Cu" signal "IN3")
		(22 "In10.Cu" signal "GND4")
		(24 "In11.Cu" signal "IN4")
		(26 "In12.Cu" signal "GND5")
		(28 "In13.Cu" signal "IN5")
		(30 "In14.Cu" signal "GND6")
		(32 "In15.Cu" signal "IN6")
		(34 "In16.Cu" signal "GND7")
		(2 "B.Cu" signal "BOTTOM")
		(9 "F.Adhes" user "F.Adhesive")
		(11 "B.Adhes" user "B.Adhesive")
		(13 "F.Paste" user "Package Geometry/Pastemask Top")
		(15 "B.Paste" user "Package Geometry/Pastemask Bottom")
		(5 "F.SilkS" user "Ref Des/Silkscreen Top")
		(7 "B.SilkS" user "Ref Des/Silkscreen Bottom")
		(1 "F.Mask" user "Board Geometry/Soldermask Top")
		(3 "B.Mask" user "Board Geometry/Soldermask Bottom")
		(17 "Dwgs.User" user "User.Drawings")
		(19 "Cmts.User" user "User.Comments")
		(21 "Eco1.User" user "User.Eco1")
		(23 "Eco2.User" user "User.Eco2")
		(25 "Edge.Cuts" user "Board Geometry/Outline")
		(27 "Margin" user)
		(31 "F.CrtYd" user "Package Geometry/Place Bound Top")
		(29 "B.CrtYd" user "Package Geometry/Place Bound Bottom")
		(35 "F.Fab" user "Ref Des/Assembly Top")
		(33 "B.Fab" user "Ref Des/Assembly Bottom")
	)
	(footprint ""
		(layer "F.Cu")
		(at 336.042 -157.734)
		(property "Reference" "R4793"
			(at 0 0 0)
			(layer "F.SilkS")
			(hide yes)
			(effects
				(font
					(size 1.27 1.27)
				)
			)
		)
		(property "Value" ""
			(at 0 0 0)
			(layer "F.Fab")
			(effects
				(font
					(size 1.27 1.27)
				)
			)
		)
		(duplicate_pad_numbers_are_jumpers no)
		(fp_line
			(start -0.7874 -0.4064)
			(end 0.7874 -0.4064)
			(stroke
				(width 0.1524)
				(type default)
			)
			(layer "F.SilkS")
		)
		(fp_line
			(start -0.7874 0.4064)
			(end -0.7874 -0.4064)
			(stroke
				(width 0.1524)
				(type default)
			)
			(layer "F.SilkS")
		)
		(fp_line
			(start 0.7874 -0.4064)
			(end 0.7874 0.4064)
			(stroke
				(width 0.1524)
				(type default)
			)
			(layer "F.SilkS")
		)
		(fp_line
			(start 0.7874 0.4064)
			(end -0.7874 0.4064)
			(stroke
				(width 0.1524)
				(type default)
			)
			(layer "F.SilkS")
		)
		(fp_line
			(start -0.67945 -0.305054)
			(end -0.12065 -0.305054)
			(stroke
				(width 0.1)
				(type default)
			)
			(layer "F.Fab")
		)
		(fp_line
			(start -0.67945 0.3048)
			(end -0.67945 -0.305054)
			(stroke
				(width 0.1)
				(type default)
			)
			(layer "F.Fab")
		)
		(fp_line
			(start -0.12065 -0.305054)
			(end -0.12065 -0.2794)
			(stroke
				(width 0.1)
				(type default)
			)
			(layer "F.Fab")
		)
		(fp_line
			(start -0.12065 -0.2794)
			(end 0.12065 -0.2794)
			(stroke
				(width 0.1)
				(type default)
			)
			(layer "F.Fab")
		)
		(fp_line
			(start -0.12065 0.2794)
			(end -0.12065 0.3048)
			(stroke
				(width 0.1)
				(type default)
			)
			(layer "F.Fab")
		)
		(fp_line
			(start -0.12065 0.3048)
			(end -0.67945 0.3048)
			(stroke
				(width 0.1)
				(type default)
			)
			(layer "F.Fab")
		)
		(fp_line
			(start 0.120396 0.2794)
			(end -0.12065 0.2794)
			(stroke
				(width 0.1)
				(type default)
			)
			(layer "F.Fab")
		)
		(fp_line
			(start 0.120396 0.3048)
			(end 0.120396 0.2794)
			(stroke
				(width 0.1)
				(type default)
			)
			(layer "F.Fab")
		)
		(fp_line
			(start 0.12065 -0.3048)
			(end 0.67945 -0.3048)
			(stroke
				(width 0.1)
				(type default)
			)
			(layer "F.Fab")
		)
		(fp_line
			(start 0.12065 -0.2794)
			(end 0.12065 -0.3048)
			(stroke
				(width 0.1)
				(type default)
			)
			(layer "F.Fab")
		)
		(fp_line
			(start 0.67945 -0.3048)
			(end 0.67945 0.3048)
			(stroke
				(width 0.1)
				(type default)
			)
			(layer "F.Fab")
		)
		(fp_line
			(start 0.67945 0.3048)
			(end 0.120396 0.3048)
			(stroke
				(width 0.1)
				(type default)
			)
			(layer "F.Fab")
		)
		(pad "1" smd circle
			(at -0.40005 0)
			(size 0 0)
			(layers "F.Cu" "F.Mask" "F.Paste")
			(net "P3V3_AUX")
		)
		(pad "2" smd circle
			(at 0.40005 0)
			(size 0 0)
			(layers "F.Cu" "F.Mask" "F.Paste")
			(net "RST_PEX_SSD12_PERST_R_N")
		)
	)
	(footprint ""
		(layer "F.Cu")
		(at 28.04922 -290.595812 -90)
		(property "Reference" "C3064"
			(at 0 0 270)
			(layer "F.SilkS")
			(hide yes)
			(effects
				(font
					(size 1.27 1.27)
				)
			)
		)
		(property "Value" ""
			(at 0 0 270)
			(layer "F.Fab")
			(effects
				(font
					(size 1.27 1.27)
				)
			)
		)
		(duplicate_pad_numbers_are_jumpers no)
		(fp_line
			(start -0.299974 0.150114)
			(end -0.299974 -0.150114)
			(stroke
				(width 0.1)
				(type default)
			)
			(layer "F.Fab")
		)
		(fp_line
			(start 0.299974 0.150114)
			(end -0.299974 0.150114)
			(stroke
				(width 0.1)
				(type default)
			)
			(layer "F.Fab")
		)
		(fp_line
			(start -0.299974 -0.150114)
			(end 0.299974 -0.150114)
			(stroke
				(width 0.1)
				(type default)
			)
			(layer "F.Fab")
		)
		(fp_line
			(start 0.299974 -0.150114)
			(end 0.299974 0.150114)
			(stroke
				(width 0.1)
				(type default)
			)
			(layer "F.Fab")
		)
		(pad "1" smd rect
			(at -0.2667 0 270)
			(size 0.3048 0.381)
			(layers "F.Cu" "F.Mask" "F.Paste")
			(net "P1V8_PLL0_PEX0")
		)
		(pad "2" smd rect
			(at 0.2667 0 270)
			(size 0.3048 0.381)
			(layers "F.Cu" "F.Mask" "F.Paste")
			(net "GND")
		)
	)
	(footprint ""
		(layer "F.Cu")
		(at 368.734594 -30.94609 180)
		(property "Reference" "C702"
			(at 0 0 180)
			(layer "F.SilkS")
			(hide yes)
			(effects
				(font
					(size 1.27 1.27)
				)
			)
		)
		(property "Value" ""
			(at 0 0 180)
			(layer "F.Fab")
			(effects
				(font
					(size 1.27 1.27)
				)
			)
		)
		(duplicate_pad_numbers_are_jumpers no)
		(fp_line
			(start 0.299974 0.150114)
			(end -0.299974 0.150114)
			(stroke
				(width 0.1)
				(type default)
			)
			(layer "F.Fab")
		)
		(fp_line
			(start 0.299974 -0.150114)
			(end 0.299974 0.150114)
			(stroke
				(width 0.1)
				(type default)
			)
			(layer "F.Fab")
		)
		(fp_line
			(start -0.299974 0.150114)
			(end -0.299974 -0.150114)
			(stroke
				(width 0.1)
				(type default)
			)
			(layer "F.Fab")
		)
		(fp_line
			(start -0.299974 -0.150114)
			(end 0.299974 -0.150114)
			(stroke
				(width 0.1)
				(type default)
			)
			(layer "F.Fab")
		)
		(pad "1" smd rect
			(at -0.2667 0 180)
			(size 0.3048 0.381)
			(layers "F.Cu" "F.Mask" "F.Paste")
			(net "P5E_PEX3_STN2_TX_DP<45>")
		)
		(pad "2" smd rect
			(at 0.2667 0 180)
			(size 0.3048 0.381)
			(layers "F.Cu" "F.Mask" "F.Paste")
			(net "P5E_PEX3_STN2_TX_C_DP<45>")
		)
	)
	(footprint ""
		(layer "F.Cu")
		(at 71.588122 -350.098614 90)
		(property "Reference" "C138"
			(at 0 0 90)
			(layer "F.SilkS")
			(hide yes)
			(effects
				(font
					(size 1.27 1.27)
				)
			)
		)
		(property "Value" ""
			(at 0 0 90)
			(layer "F.Fab")
			(effects
				(font
					(size 1.27 1.27)
				)
			)
		)
		(duplicate_pad_numbers_are_jumpers no)
		(fp_line
			(start 0.299974 -0.150114)
			(end 0.299974 0.150114)
			(stroke
				(width 0.1)
				(type default)
			)
			(layer "F.Fab")
		)
		(fp_line
			(start -0.299974 -0.150114)
			(end 0.299974 -0.150114)
			(stroke
				(width 0.1)
				(type default)
			)
			(layer "F.Fab")
		)
		(fp_line
			(start 0.299974 0.150114)
			(end -0.299974 0.150114)
			(stroke
				(width 0.1)
				(type default)
			)
			(layer "F.Fab")
		)
		(fp_line
			(start -0.299974 0.150114)
			(end -0.299974 -0.150114)
			(stroke
				(width 0.1)
				(type default)
			)
			(layer "F.Fab")
		)
		(pad "1" smd rect
			(at -0.2667 0 90)
			(size 0.3048 0.381)
			(layers "F.Cu" "F.Mask" "F.Paste")
			(net "P5E_PEX0_STN6_TX_DN<107>")
		)
		(pad "2" smd rect
			(at 0.2667 0 90)
			(size 0.3048 0.381)
			(layers "F.Cu" "F.Mask" "F.Paste")
			(net "P5E_PEX0_STN6_TX_C_DN<107>")
		)
	)
)
